# SCM (Grand Teton) — schematic netlist excerpt (pin names and nets, part order shuffled) for the footprints in the layout excerpt that follows; sources: Cadence DE-HDL packaged netlist, KiCad conversion of 12092022_DA0F0TMDCD0_F0T_Management_Board_D_brd_V3_OCP.brd

R183  Q_RES  0 5% CHIP  pkg 0402LF  page 34 : A = P3V3_AUX ; B = PVCCIO_AUX_PLD
R2  Q_RES  0 5% CHIP  pkg 0402LF  page 20 : A = M_BMC_DDR4_BG1 ; B = GND

(kicad_pcb
	(version 20260206)
	(generator "pcbnew")
	(generator_version "10.0")
	(general
		(thickness 1.6)
		(legacy_teardrops no)
	)
	(paper "A4")
	(title_block
		(title "12092022_DA0F0TMDCD0_F0T_Management_Board_D_brd_V3_OCP.brd")
		(comment 1 "Grand Teton / footprints 1037-1038 of 1440")
	)
	(layers
		(0 "F.Cu" signal "TOP")
		(4 "In1.Cu" signal "GND")
		(6 "In2.Cu" signal "IN1")
		(8 "In3.Cu" signal "GND1")
		(10 "In4.Cu" signal "IN2")
		(12 "In5.Cu" signal "VCC")
		(14 "In6.Cu" signal "VCC1")
		(16 "In7.Cu" signal "IN3")
		(18 "In8.Cu" signal "GND2")
		(20 "In9.Cu" signal "IN4")
		(22 "In10.Cu" signal "GND3")
		(2 "B.Cu" signal "BOTTOM")
		(9 "F.Adhes" user "F.Adhesive")
		(11 "B.Adhes" user "B.Adhesive")
		(13 "F.Paste" user "Package Geometry/Pastemask Top")
		(15 "B.Paste" user "Package Geometry/Pastemask Bottom")
		(5 "F.SilkS" user "Ref Des/Silkscreen Top")
		(7 "B.SilkS" user "Ref Des/Silkscreen Bottom")
		(1 "F.Mask" user "Board Geometry/Soldermask Top")
		(3 "B.Mask" user "Board Geometry/Soldermask Bottom")
		(17 "Dwgs.User" user "User.Drawings")
		(19 "Cmts.User" user "User.Comments")
		(21 "Eco1.User" user "User.Eco1")
		(23 "Eco2.User" user "User.Eco2")
		(25 "Edge.Cuts" user "Board Geometry/Outline")
		(27 "Margin" user)
		(31 "F.CrtYd" user "Package Geometry/Place Bound Top")
		(29 "B.CrtYd" user "Package Geometry/Place Bound Bottom")
		(35 "F.Fab" user "Ref Des/Assembly Top")
		(33 "B.Fab" user "Ref Des/Assembly Bottom")
	)
	(footprint ""
		(layer "B.Cu")
		(at 81.129886 -45.054012 180)
		(property "Reference" "R2"
			(at 0 0 0)
			(layer "B.SilkS")
			(hide yes)
			(effects
				(font
					(size 1.27 1.27)
				)
				(justify mirror)
			)
		)
		(property "Value" ""
			(at 0 0 0)
			(layer "B.Fab")
			(effects
				(font
					(size 1.27 1.27)
				)
				(justify mirror)
			)
		)
		(duplicate_pad_numbers_are_jumpers no)
		(fp_line
			(start 0.7874 0.4064)
			(end 0.7874 -0.4064)
			(stroke
				(width 0.1524)
				(type default)
			)
			(layer "B.SilkS")
		)
		(fp_line
			(start 0.7874 -0.4064)
			(end -0.7874 -0.4064)
			(stroke
				(width 0.1524)
				(type default)
			)
			(layer "B.SilkS")
		)
		(fp_line
			(start -0.7874 0.4064)
			(end 0.7874 0.4064)
			(stroke
				(width 0.1524)
				(type default)
			)
			(layer "B.SilkS")
		)
		(fp_line
			(start -0.7874 -0.4064)
			(end -0.7874 0.4064)
			(stroke
				(width 0.1524)
				(type default)
			)
			(layer "B.SilkS")
		)
		(fp_line
			(start 0.67945 0.3048)
			(end 0.67945 -0.305054)
			(stroke
				(width 0.1)
				(type default)
			)
			(layer "B.Fab")
		)
		(fp_line
			(start 0.67945 -0.305054)
			(end 0.12065 -0.305054)
			(stroke
				(width 0.1)
				(type default)
			)
			(layer "B.Fab")
		)
		(fp_line
			(start 0.12065 0.3048)
			(end 0.67945 0.3048)
			(stroke
				(width 0.1)
				(type default)
			)
			(layer "B.Fab")
		)
		(fp_line
			(start 0.12065 0.2794)
			(end 0.12065 0.3048)
			(stroke
				(width 0.1)
				(type default)
			)
			(layer "B.Fab")
		)
		(fp_line
			(start 0.12065 -0.2794)
			(end -0.12065 -0.2794)
			(stroke
				(width 0.1)
				(type default)
			)
			(layer "B.Fab")
		)
		(fp_line
			(start 0.12065 -0.305054)
			(end 0.12065 -0.2794)
			(stroke
				(width 0.1)
				(type default)
			)
			(layer "B.Fab")
		)
		(fp_line
			(start -0.120396 0.3048)
			(end -0.120396 0.2794)
			(stroke
				(width 0.1)
				(type default)
			)
			(layer "B.Fab")
		)
		(fp_line
			(start -0.120396 0.2794)
			(end 0.12065 0.2794)
			(stroke
				(width 0.1)
				(type default)
			)
			(layer "B.Fab")
		)
		(fp_line
			(start -0.12065 -0.2794)
			(end -0.12065 -0.3048)
			(stroke
				(width 0.1)
				(type default)
			)
			(layer "B.Fab")
		)
		(fp_line
			(start -0.12065 -0.3048)
			(end -0.67945 -0.3048)
			(stroke
				(width 0.1)
				(type default)
			)
			(layer "B.Fab")
		)
		(fp_line
			(start -0.67945 0.3048)
			(end -0.120396 0.3048)
			(stroke
				(width 0.1)
				(type default)
			)
			(layer "B.Fab")
		)
		(fp_line
			(start -0.67945 -0.3048)
			(end -0.67945 0.3048)
			(stroke
				(width 0.1)
				(type default)
			)
			(layer "B.Fab")
		)
		(pad "1" smd circle
			(at 0.40005 0)
			(size 0 0)
			(layers "B.Cu" "B.Mask" "B.Paste")
			(net "M_BMC_DDR4_BG1")
		)
		(pad "2" smd circle
			(at -0.40005 0)
			(size 0 0)
			(layers "B.Cu" "B.Mask" "B.Paste")
			(net "GND")
		)
	)
	(footprint ""
		(layer "B.Cu")
		(at 32.766 -91.821)
		(property "Reference" "R183"
			(at 0 0 0)
			(layer "B.SilkS")
			(hide yes)
			(effects
				(font
					(size 1.27 1.27)
				)
				(justify mirror)
			)
		)
		(property "Value" ""
			(at 0 0 0)
			(layer "B.Fab")
			(effects
				(font
					(size 1.27 1.27)
				)
				(justify mirror)
			)
		)
		(duplicate_pad_numbers_are_jumpers no)
		(fp_line
			(start -0.7874 -0.4064)
			(end -0.7874 0.4064)
			(stroke
				(width 0.1524)
				(type default)
			)
			(layer "B.SilkS")
		)
		(fp_line
			(start -0.7874 0.4064)
			(end 0.7874 0.4064)
			(stroke
				(width 0.1524)
				(type default)
			)
			(layer "B.SilkS")
		)
		(fp_line
			(start 0.7874 -0.4064)
			(end -0.7874 -0.4064)
			(stroke
				(width 0.1524)
				(type default)
			)
			(layer "B.SilkS")
		)
		(fp_line
			(start 0.7874 0.4064)
			(end 0.7874 -0.4064)
			(stroke
				(width 0.1524)
				(type default)
			)
			(layer "B.SilkS")
		)
		(fp_line
			(start -0.67945 -0.3048)
			(end -0.67945 0.3048)
			(stroke
				(width 0.1)
				(type default)
			)
			(layer "B.Fab")
		)
		(fp_line
			(start -0.67945 0.3048)
			(end -0.120396 0.3048)
			(stroke
				(width 0.1)
				(type default)
			)
			(layer "B.Fab")
		)
		(fp_line
			(start -0.12065 -0.3048)
			(end -0.67945 -0.3048)
			(stroke
				(width 0.1)
				(type default)
			)
			(layer "B.Fab")
		)
		(fp_line
			(start -0.12065 -0.2794)
			(end -0.12065 -0.3048)
			(stroke
				(width 0.1)
				(type default)
			)
			(layer "B.Fab")
		)
		(fp_line
			(start -0.120396 0.2794)
			(end 0.12065 0.2794)
			(stroke
				(width 0.1)
				(type default)
			)
			(layer "B.Fab")
		)
		(fp_line
			(start -0.120396 0.3048)
			(end -0.120396 0.2794)
			(stroke
				(width 0.1)
				(type default)
			)
			(layer "B.Fab")
		)
		(fp_line
			(start 0.12065 -0.305054)
			(end 0.12065 -0.2794)
			(stroke
				(width 0.1)
				(type default)
			)
			(layer "B.Fab")
		)
		(fp_line
			(start 0.12065 -0.2794)
			(end -0.12065 -0.2794)
			(stroke
				(width 0.1)
				(type default)
			)
			(layer "B.Fab")
		)
		(fp_line
			(start 0.12065 0.2794)
			(end 0.12065 0.3048)
			(stroke
				(width 0.1)
				(type default)
			)
			(layer "B.Fab")
		)
		(fp_line
			(start 0.12065 0.3048)
			(end 0.67945 0.3048)
			(stroke
				(width 0.1)
				(type default)
			)
			(layer "B.Fab")
		)
		(fp_line
			(start 0.67945 -0.305054)
			(end 0.12065 -0.305054)
			(stroke
				(width 0.1)
				(type default)
			)
			(layer "B.Fab")
		)
		(fp_line
			(start 0.67945 0.3048)
			(end 0.67945 -0.305054)
			(stroke
				(width 0.1)
				(type default)
			)
			(layer "B.Fab")
		)
		(pad "1" smd circle
			(at 0.40005 0 180)
			(size 0 0)
			(layers "B.Cu" "B.Mask" "B.Paste")
			(net "P3V3_AUX")
		)
		(pad "2" smd circle
			(at -0.40005 0 180)
			(size 0 0)
			(layers "B.Cu" "B.Mask" "B.Paste")
			(net "PVCCIO_AUX_PLD")
		)
	)
)
